(kicad_pcb
	(version 20260206)
	(generator "pcbnew")
	(generator_version "10.0")
	(general
		(thickness 1.6)
		(legacy_teardrops no)
	)
	(paper "A4")
	(title_block
		(title "01162023_DA0F0TEBIF0_F0T_Expander_BD_F_brd_V02_OCP.brd")
		(comment 1 "Grand Teton / footprints 2997-3001 of 9728")
	)
	(layers
		(0 "F.Cu" signal "TOP")
		(4 "In1.Cu" signal "GND")
		(6 "In2.Cu" signal "VCC")
		(8 "In3.Cu" signal "VCC1")
		(10 "In4.Cu" signal "GND1")
		(12 "In5.Cu" signal "IN1")
		(14 "In6.Cu" signal "GND2")
		(16 "In7.Cu" signal "IN2")
		(18 "In8.Cu" signal "GND3")
		(20 "In9.Cu" signal "IN3")
		(22 "In10.Cu" signal "GND4")
		(24 "In11.Cu" signal "IN4")
		(26 "In12.Cu" signal "GND5")
		(28 "In13.Cu" signal "IN5")
		(30 "In14.Cu" signal "GND6")
		(32 "In15.Cu" signal "IN6")
		(34 "In16.Cu" signal "GND7")
		(2 "B.Cu" signal "BOTTOM")
		(9 "F.Adhes" user "F.Adhesive")
		(11 "B.Adhes" user "B.Adhesive")
		(13 "F.Paste" user "Package Geometry/Pastemask Top")
		(15 "B.Paste" user "Package Geometry/Pastemask Bottom")
		(5 "F.SilkS" user "Ref Des/Silkscreen Top")
		(7 "B.SilkS" user "Ref Des/Silkscreen Bottom")
		(1 "F.Mask" user "Board Geometry/Soldermask Top")
		(3 "B.Mask" user "Board Geometry/Soldermask Bottom")
		(17 "Dwgs.User" user "User.Drawings")
		(19 "Cmts.User" user "User.Comments")
		(21 "Eco1.User" user "User.Eco1")
		(23 "Eco2.User" user "User.Eco2")
		(25 "Edge.Cuts" user "Board Geometry/Outline")
		(27 "Margin" user)
		(31 "F.CrtYd" user "Package Geometry/Place Bound Top")
		(29 "B.CrtYd" user "Package Geometry/Place Bound Bottom")
		(35 "F.Fab" user "Ref Des/Assembly Top")
		(33 "B.Fab" user "Ref Des/Assembly Bottom")
	)
	(footprint ""
		(layer "F.Cu")
		(at 148.991066 -55.663846 90)
		(property "Reference" "PU57"
			(at -1.267206 2.93878 90)
			(unlocked yes)
			(layer "F.SilkS")
			(effects
				(font
					(size 0.7874 0.5842)
					(thickness 0.1524)
				)
				(justify left)
			)
		)
		(property "Value" ""
			(at 0 0 90)
			(layer "F.Fab")
			(effects
				(font
					(size 1.27 1.27)
				)
			)
		)
		(duplicate_pad_numbers_are_jumpers no)
		(fp_line
			(start 1.943608 -1.549908)
			(end 1.943608 1.549908)
			(stroke
				(width 0.1524)
				(type default)
			)
			(layer "F.SilkS")
		)
		(fp_line
			(start -1.943608 -1.549908)
			(end 1.943608 -1.549908)
			(stroke
				(width 0.1524)
				(type default)
			)
			(layer "F.SilkS")
		)
		(fp_line
			(start 1.943608 1.549908)
			(end -1.943608 1.549908)
			(stroke
				(width 0.1524)
				(type default)
			)
			(layer "F.SilkS")
		)
		(fp_line
			(start -1.943608 1.549908)
			(end -1.943608 -1.549908)
			(stroke
				(width 0.1524)
				(type default)
			)
			(layer "F.SilkS")
		)
		(fp_poly
			(pts
				(xy -2.019808 -1.549908) (xy -1.257808 -1.549908) (xy -1.257808 -1.880108) (xy -2.019808 -1.880108)
			)
			(stroke
				(width 0)
				(type default)
			)
			(fill yes)
			(layer "F.SilkS")
		)
		(fp_line
			(start 1.549908 -1.549908)
			(end 1.549908 1.549908)
			(stroke
				(width 0.1)
				(type default)
			)
			(layer "F.Fab")
		)
		(fp_line
			(start -1.549908 -1.549908)
			(end 1.549908 -1.549908)
			(stroke
				(width 0.1)
				(type default)
			)
			(layer "F.Fab")
		)
		(fp_line
			(start 1.549908 1.549908)
			(end -1.549908 1.549908)
			(stroke
				(width 0.1)
				(type default)
			)
			(layer "F.Fab")
		)
		(fp_line
			(start -1.549908 1.549908)
			(end -1.549908 -1.549908)
			(stroke
				(width 0.1)
				(type default)
			)
			(layer "F.Fab")
		)
		(fp_poly
			(pts
				(xy -2.019808 -1.549908) (xy -1.257808 -1.549908) (xy -1.257808 -1.880108) (xy -2.019808 -1.880108)
			)
			(stroke
				(width 0)
				(type default)
			)
			(fill yes)
			(layer "F.Fab")
		)
		(pad "1" smd rect
			(at -1.500124 -1.249934)
			(size 0.2794 0.6096)
			(layers "F.Cu" "F.Mask" "F.Paste")
			(net "P3V3_SSD5")
		)
		(pad "2" smd rect
			(at -1.500124 -0.750062)
			(size 0.2794 0.6096)
			(layers "F.Cu" "F.Mask" "F.Paste")
			(net "P3V3_SSD5")
		)
		(pad "3" smd rect
			(at -1.500124 -0.249936)
			(size 0.2794 0.6096)
			(layers "F.Cu" "F.Mask" "F.Paste")
			(net "P3V3_SSD5")
		)
		(pad "4" smd rect
			(at -1.500124 0.249936)
			(size 0.2794 0.6096)
			(layers "F.Cu" "F.Mask" "F.Paste")
			(net "P3V3_SSD5")
		)
		(pad "5" smd rect
			(at -1.500124 0.750062)
			(size 0.2794 0.6096)
			(layers "F.Cu" "F.Mask" "F.Paste")
			(net "P3V3_SSD5")
		)
		(pad "6" smd rect
			(at -1.500124 1.249934)
			(size 0.2794 0.6096)
			(layers "F.Cu" "F.Mask" "F.Paste")
			(net "GND")
		)
		(pad "7" smd rect
			(at 1.500124 1.249934)
			(size 0.2794 0.6096)
			(layers "F.Cu" "F.Mask" "F.Paste")
			(net "P3V3_SSD5_SS")
		)
		(pad "8" smd rect
			(at 1.500124 0.750062)
			(size 0.2794 0.6096)
			(layers "F.Cu" "F.Mask" "F.Paste")
			(net "PWRGD_P3V3_SSD5")
		)
		(pad "9" smd rect
			(at 1.500124 0.249936)
			(size 0.2794 0.6096)
			(layers "F.Cu" "F.Mask" "F.Paste")
			(net "P3V3_SSD5_OCP")
		)
		(pad "10" smd rect
			(at 1.500124 -0.249936)
			(size 0.2794 0.6096)
			(layers "F.Cu" "F.Mask" "F.Paste")
			(net "P5V_AUX")
		)
		(pad "11" smd rect
			(at 1.500124 -0.750062)
			(size 0.2794 0.6096)
			(layers "F.Cu" "F.Mask" "F.Paste")
			(net "SSD5_AUX_P3V3_EN_R")
		)
		(pad "12" smd rect
			(at 1.500124 -1.249934)
			(size 0.2794 0.6096)
			(layers "F.Cu" "F.Mask" "F.Paste")
			(net "P3V3_AUX")
		)
		(pad "13" smd rect
			(at 0 0 90)
			(size 1.9812 2.7178)
			(layers "F.Cu" "F.Mask" "F.Paste")
			(net "P3V3_AUX")
		)
		(zone
			(layer "F.Cu")
			(hatch none 0.5)
			(connect_pads
				(clearance 0)
			)
			(min_thickness 0.25)
			(keepout
				(tracks not_allowed)
				(vias allowed)
				(pads allowed)
				(copperpour not_allowed)
				(footprints allowed)
			)
			(placement
				(enabled no)
				(sheetname "")
			)
			(fill
				(thermal_gap 0.5)
				(thermal_bridge_width 0.5)
				(island_removal_mode 0)
			)
			(polygon
				(pts
					(xy 147.441666 -56.806846) (xy 147.568666 -56.806846) (xy 150.540466 -56.806846) (xy 150.540974 -56.806846)
					(xy 150.540974 -54.520846) (xy 150.540466 -54.520846) (xy 150.413466 -54.520846) (xy 148.991066 -54.520846)
					(xy 148.991066 -54.622446) (xy 150.413466 -54.622446) (xy 150.413466 -56.705246) (xy 147.568666 -56.705246)
					(xy 147.568666 -54.622446) (xy 148.965666 -54.622446) (xy 148.965666 -54.520846) (xy 147.568666 -54.520846)
					(xy 147.441666 -54.520846) (xy 147.441158 -54.520846) (xy 147.441158 -56.806846)
				)
			)
		)
	)
	(footprint ""
		(layer "F.Cu")
		(at 230.156512 -243.22786 90)
		(property "Reference" "R6257"
			(at 0 0 90)
			(layer "F.SilkS")
			(hide yes)
			(effects
				(font
					(size 1.27 1.27)
				)
			)
		)
		(property "Value" ""
			(at 0 0 90)
			(layer "F.Fab")
			(effects
				(font
					(size 1.27 1.27)
				)
			)
		)
		(duplicate_pad_numbers_are_jumpers no)
		(fp_line
			(start 0.7874 -0.4064)
			(end 0.7874 0.4064)
			(stroke
				(width 0.1524)
				(type default)
			)
			(layer "F.SilkS")
		)
		(fp_line
			(start -0.7874 -0.4064)
			(end 0.7874 -0.4064)
			(stroke
				(width 0.1524)
				(type default)
			)
			(layer "F.SilkS")
		)
		(fp_line
			(start 0.7874 0.4064)
			(end -0.7874 0.4064)
			(stroke
				(width 0.1524)
				(type default)
			)
			(layer "F.SilkS")
		)
		(fp_line
			(start -0.7874 0.4064)
			(end -0.7874 -0.4064)
			(stroke
				(width 0.1524)
				(type default)
			)
			(layer "F.SilkS")
		)
		(fp_line
			(start -0.12065 -0.305054)
			(end -0.12065 -0.2794)
			(stroke
				(width 0.1)
				(type default)
			)
			(layer "F.Fab")
		)
		(fp_line
			(start -0.67945 -0.305054)
			(end -0.12065 -0.305054)
			(stroke
				(width 0.1)
				(type default)
			)
			(layer "F.Fab")
		)
		(fp_line
			(start 0.67945 -0.3048)
			(end 0.67945 0.3048)
			(stroke
				(width 0.1)
				(type default)
			)
			(layer "F.Fab")
		)
		(fp_line
			(start 0.12065 -0.3048)
			(end 0.67945 -0.3048)
			(stroke
				(width 0.1)
				(type default)
			)
			(layer "F.Fab")
		)
		(fp_line
			(start 0.12065 -0.2794)
			(end 0.12065 -0.3048)
			(stroke
				(width 0.1)
				(type default)
			)
			(layer "F.Fab")
		)
		(fp_line
			(start -0.12065 -0.2794)
			(end 0.12065 -0.2794)
			(stroke
				(width 0.1)
				(type default)
			)
			(layer "F.Fab")
		)
		(fp_line
			(start 0.120396 0.2794)
			(end -0.12065 0.2794)
			(stroke
				(width 0.1)
				(type default)
			)
			(layer "F.Fab")
		)
		(fp_line
			(start -0.12065 0.2794)
			(end -0.12065 0.3048)
			(stroke
				(width 0.1)
				(type default)
			)
			(layer "F.Fab")
		)
		(fp_line
			(start 0.67945 0.3048)
			(end 0.120396 0.3048)
			(stroke
				(width 0.1)
				(type default)
			)
			(layer "F.Fab")
		)
		(fp_line
			(start 0.120396 0.3048)
			(end 0.120396 0.2794)
			(stroke
				(width 0.1)
				(type default)
			)
			(layer "F.Fab")
		)
		(fp_line
			(start -0.12065 0.3048)
			(end -0.67945 0.3048)
			(stroke
				(width 0.1)
				(type default)
			)
			(layer "F.Fab")
		)
		(fp_line
			(start -0.67945 0.3048)
			(end -0.67945 -0.305054)
			(stroke
				(width 0.1)
				(type default)
			)
			(layer "F.Fab")
		)
		(pad "1" smd circle
			(at -0.40005 0 90)
			(size 0 0)
			(layers "F.Cu" "F.Mask" "F.Paste")
			(net "P3V3_AUX")
		)
		(pad "2" smd circle
			(at 0.40005 0 90)
			(size 0 0)
			(layers "F.Cu" "F.Mask" "F.Paste")
			(net "BIC_UART_BMC_SEL_R")
		)
	)
	(footprint ""
		(layer "F.Cu")
		(at 426.543724 -44.87291)
		(property "Reference" "R660"
			(at 0 0 0)
			(layer "F.SilkS")
			(hide yes)
			(effects
				(font
					(size 1.27 1.27)
				)
			)
		)
		(property "Value" ""
			(at 0 0 0)
			(layer "F.Fab")
			(effects
				(font
					(size 1.27 1.27)
				)
			)
		)
		(duplicate_pad_numbers_are_jumpers no)
		(fp_line
			(start -0.7874 -0.4064)
			(end 0.7874 -0.4064)
			(stroke
				(width 0.1524)
				(type default)
			)
			(layer "F.SilkS")
		)
		(fp_line
			(start -0.7874 0.4064)
			(end -0.7874 -0.4064)
			(stroke
				(width 0.1524)
				(type default)
			)
			(layer "F.SilkS")
		)
		(fp_line
			(start 0.7874 -0.4064)
			(end 0.7874 0.4064)
			(stroke
				(width 0.1524)
				(type default)
			)
			(layer "F.SilkS")
		)
		(fp_line
			(start 0.7874 0.4064)
			(end -0.7874 0.4064)
			(stroke
				(width 0.1524)
				(type default)
			)
			(layer "F.SilkS")
		)
		(fp_line
			(start -0.67945 -0.305054)
			(end -0.12065 -0.305054)
			(stroke
				(width 0.1)
				(type default)
			)
			(layer "F.Fab")
		)
		(fp_line
			(start -0.67945 0.3048)
			(end -0.67945 -0.305054)
			(stroke
				(width 0.1)
				(type default)
			)
			(layer "F.Fab")
		)
		(fp_line
			(start -0.12065 -0.305054)
			(end -0.12065 -0.2794)
			(stroke
				(width 0.1)
				(type default)
			)
			(layer "F.Fab")
		)
		(fp_line
			(start -0.12065 -0.2794)
			(end 0.12065 -0.2794)
			(stroke
				(width 0.1)
				(type default)
			)
			(layer "F.Fab")
		)
		(fp_line
			(start -0.12065 0.2794)
			(end -0.12065 0.3048)
			(stroke
				(width 0.1)
				(type default)
			)
			(layer "F.Fab")
		)
		(fp_line
			(start -0.12065 0.3048)
			(end -0.67945 0.3048)
			(stroke
				(width 0.1)
				(type default)
			)
			(layer "F.Fab")
		)
		(fp_line
			(start 0.120396 0.2794)
			(end -0.12065 0.2794)
			(stroke
				(width 0.1)
				(type default)
			)
			(layer "F.Fab")
		)
		(fp_line
			(start 0.120396 0.3048)
			(end 0.120396 0.2794)
			(stroke
				(width 0.1)
				(type default)
			)
			(layer "F.Fab")
		)
		(fp_line
			(start 0.12065 -0.3048)
			(end 0.67945 -0.3048)
			(stroke
				(width 0.1)
				(type default)
			)
			(layer "F.Fab")
		)
		(fp_line
			(start 0.12065 -0.2794)
			(end 0.12065 -0.3048)
			(stroke
				(width 0.1)
				(type default)
			)
			(layer "F.Fab")
		)
		(fp_line
			(start 0.67945 -0.3048)
			(end 0.67945 0.3048)
			(stroke
				(width 0.1)
				(type default)
			)
			(layer "F.Fab")
		)
		(fp_line
			(start 0.67945 0.3048)
			(end 0.120396 0.3048)
			(stroke
				(width 0.1)
				(type default)
			)
			(layer "F.Fab")
		)
		(pad "1" smd circle
			(at -0.40005 0)
			(size 0 0)
			(layers "F.Cu" "F.Mask" "F.Paste")
			(net "SSD14_ADC_A0")
		)
		(pad "2" smd circle
			(at 0.40005 0)
			(size 0 0)
			(layers "F.Cu" "F.Mask" "F.Paste")
			(net "P3V3_AUX")
		)
	)
	(footprint ""
		(layer "F.Cu")
		(at 284.467808 -56.353456)
		(property "Reference" "C2871"
			(at 0 0 0)
			(layer "F.SilkS")
			(hide yes)
			(effects
				(font
					(size 1.27 1.27)
				)
			)
		)
		(property "Value" ""
			(at 0 0 0)
			(layer "F.Fab")
			(effects
				(font
					(size 1.27 1.27)
				)
			)
		)
		(duplicate_pad_numbers_are_jumpers no)
		(fp_line
			(start -0.7874 -0.4064)
			(end 0.7874 -0.4064)
			(stroke
				(width 0.1524)
				(type default)
			)
			(layer "F.SilkS")
		)
		(fp_line
			(start -0.7874 0.4064)
			(end -0.7874 -0.4064)
			(stroke
				(width 0.1524)
				(type default)
			)
			(layer "F.SilkS")
		)
		(fp_line
			(start 0.7874 -0.4064)
			(end 0.7874 0.4064)
			(stroke
				(width 0.1524)
				(type default)
			)
			(layer "F.SilkS")
		)
		(fp_line
			(start 0.7874 0.4064)
			(end -0.7874 0.4064)
			(stroke
				(width 0.1524)
				(type default)
			)
			(layer "F.SilkS")
		)
		(fp_line
			(start -0.67945 -0.305054)
			(end -0.12065 -0.305054)
			(stroke
				(width 0.1)
				(type default)
			)
			(layer "F.Fab")
		)
		(fp_line
			(start -0.67945 0.3048)
			(end -0.67945 -0.305054)
			(stroke
				(width 0.1)
				(type default)
			)
			(layer "F.Fab")
		)
		(fp_line
			(start -0.12065 -0.305054)
			(end -0.12065 -0.2794)
			(stroke
				(width 0.1)
				(type default)
			)
			(layer "F.Fab")
		)
		(fp_line
			(start -0.12065 -0.2794)
			(end 0.12065 -0.2794)
			(stroke
				(width 0.1)
				(type default)
			)
			(layer "F.Fab")
		)
		(fp_line
			(start -0.12065 0.2794)
			(end -0.12065 0.3048)
			(stroke
				(width 0.1)
				(type default)
			)
			(layer "F.Fab")
		)
		(fp_line
			(start -0.12065 0.3048)
			(end -0.67945 0.3048)
			(stroke
				(width 0.1)
				(type default)
			)
			(layer "F.Fab")
		)
		(fp_line
			(start 0.120396 0.2794)
			(end -0.12065 0.2794)
			(stroke
				(width 0.1)
				(type default)
			)
			(layer "F.Fab")
		)
		(fp_line
			(start 0.120396 0.3048)
			(end 0.120396 0.2794)
			(stroke
				(width 0.1)
				(type default)
			)
			(layer "F.Fab")
		)
		(fp_line
			(start 0.12065 -0.3048)
			(end 0.67945 -0.3048)
			(stroke
				(width 0.1)
				(type default)
			)
			(layer "F.Fab")
		)
		(fp_line
			(start 0.12065 -0.2794)
			(end 0.12065 -0.3048)
			(stroke
				(width 0.1)
				(type default)
			)
			(layer "F.Fab")
		)
		(fp_line
			(start 0.67945 -0.3048)
			(end 0.67945 0.3048)
			(stroke
				(width 0.1)
				(type default)
			)
			(layer "F.Fab")
		)
		(fp_line
			(start 0.67945 0.3048)
			(end 0.120396 0.3048)
			(stroke
				(width 0.1)
				(type default)
			)
			(layer "F.Fab")
		)
		(pad "1" smd circle
			(at -0.40005 0)
			(size 0 0)
			(layers "F.Cu" "F.Mask" "F.Paste")
			(net "SSD9_PWR_EN_R")
		)
		(pad "2" smd circle
			(at 0.40005 0)
			(size 0 0)
			(layers "F.Cu" "F.Mask" "F.Paste")
			(net "GND")
		)
	)
	(footprint ""
		(layer "F.Cu")
		(at 127.624332 -259.145532 180)
		(property "Reference" "PR7165"
			(at 0 0 180)
			(layer "F.SilkS")
			(hide yes)
			(effects
				(font
					(size 1.27 1.27)
				)
			)
		)
		(property "Value" ""
			(at 0 0 180)
			(layer "F.Fab")
			(effects
				(font
					(size 1.27 1.27)
				)
			)
		)
		(duplicate_pad_numbers_are_jumpers no)
		(fp_line
			(start 0.7874 0.4064)
			(end -0.7874 0.4064)
			(stroke
				(width 0.1524)
				(type default)
			)
			(layer "F.SilkS")
		)
		(fp_line
			(start 0.7874 -0.4064)
			(end 0.7874 0.4064)
			(stroke
				(width 0.1524)
				(type default)
			)
			(layer "F.SilkS")
		)
		(fp_line
			(start -0.7874 0.4064)
			(end -0.7874 -0.4064)
			(stroke
				(width 0.1524)
				(type default)
			)
			(layer "F.SilkS")
		)
		(fp_line
			(start -0.7874 -0.4064)
			(end 0.7874 -0.4064)
			(stroke
				(width 0.1524)
				(type default)
			)
			(layer "F.SilkS")
		)
		(fp_line
			(start 0.67945 0.3048)
			(end 0.120396 0.3048)
			(stroke
				(width 0.1)
				(type default)
			)
			(layer "F.Fab")
		)
		(fp_line
			(start 0.67945 -0.3048)
			(end 0.67945 0.3048)
			(stroke
				(width 0.1)
				(type default)
			)
			(layer "F.Fab")
		)
		(fp_line
			(start 0.12065 -0.2794)
			(end 0.12065 -0.3048)
			(stroke
				(width 0.1)
				(type default)
			)
			(layer "F.Fab")
		)
		(fp_line
			(start 0.12065 -0.3048)
			(end 0.67945 -0.3048)
			(stroke
				(width 0.1)
				(type default)
			)
			(layer "F.Fab")
		)
		(fp_line
			(start 0.120396 0.3048)
			(end 0.120396 0.2794)
			(stroke
				(width 0.1)
				(type default)
			)
			(layer "F.Fab")
		)
		(fp_line
			(start 0.120396 0.2794)
			(end -0.12065 0.2794)
			(stroke
				(width 0.1)
				(type default)
			)
			(layer "F.Fab")
		)
		(fp_line
			(start -0.12065 0.3048)
			(end -0.67945 0.3048)
			(stroke
				(width 0.1)
				(type default)
			)
			(layer "F.Fab")
		)
		(fp_line
			(start -0.12065 0.2794)
			(end -0.12065 0.3048)
			(stroke
				(width 0.1)
				(type default)
			)
			(layer "F.Fab")
		)
		(fp_line
			(start -0.12065 -0.2794)
			(end 0.12065 -0.2794)
			(stroke
				(width 0.1)
				(type default)
			)
			(layer "F.Fab")
		)
		(fp_line
			(start -0.12065 -0.305054)
			(end -0.12065 -0.2794)
			(stroke
				(width 0.1)
				(type default)
			)
			(layer "F.Fab")
		)
		(fp_line
			(start -0.67945 0.3048)
			(end -0.67945 -0.305054)
			(stroke
				(width 0.1)
				(type default)
			)
			(layer "F.Fab")
		)
		(fp_line
			(start -0.67945 -0.305054)
			(end -0.12065 -0.305054)
			(stroke
				(width 0.1)
				(type default)
			)
			(layer "F.Fab")
		)
		(pad "1" smd circle
			(at -0.40005 0 180)
			(size 0 0)
			(layers "F.Cu" "F.Mask" "F.Paste")
			(net "GND")
		)
		(pad "2" smd circle
			(at 0.40005 0 180)
			(size 0 0)
			(layers "F.Cu" "F.Mask" "F.Paste")
			(net "NC_P0V8_PEX0_SVID_ALERT_N_R")
		)
	)
)
